# S9S_MB_2U (Grand Teton) — schematic netlist excerpt (pin names and nets, part order shuffled) for the footprints in the layout excerpt that follows; sources: Cadence DE-HDL packaged netlist, KiCad conversion of 03242023_DA0F0TMBIJ0_F0T_Motherboard_J_brd_V01_OCP.brd

U98  PCA9306DP1  IC  pkg TSSOP8_3  page 194
  GND  = GND
  VREF1  = P1V8_PCH_AUX
  SCL1  = SMB_M2_P0_1V8AUX_SCL_R
  SDA1  = SMB_M2_P0_1V8AUX_SDA_R
  SDA2  = SMB_SENSOR_M2_P0_3V3AUX_SDA
  SCL2  = SMB_SENSOR_M2_P0_3V3AUX_SCL
  VREF2  = SMB_PCIE_M2_0_EN
  EN  = SMB_PCIE_M2_0_EN

C252  Q_CAP  10UF 6.3V 20% X6S  pkg C0402  page 77 : A = PVCCIN_CPU1 ; B = GND

(kicad_pcb
	(version 20260206)
	(generator "pcbnew")
	(generator_version "10.0")
	(general
		(thickness 1.6)
		(legacy_teardrops no)
	)
	(paper "A4")
	(title_block
		(title "03242023_DA0F0TMBIJ0_F0T_Motherboard_J_brd_V01_OCP.brd")
		(comment 1 "Grand Teton / footprints 2691-2692 of 6105")
	)
	(layers
		(0 "F.Cu" signal "TOP")
		(4 "In1.Cu" signal "GND")
		(6 "In2.Cu" signal "IN1")
		(8 "In3.Cu" signal "GND1")
		(10 "In4.Cu" signal "IN2")
		(12 "In5.Cu" signal "GND2")
		(14 "In6.Cu" signal "IN3")
		(16 "In7.Cu" signal "GND3")
		(18 "In8.Cu" signal "VCC")
		(20 "In9.Cu" signal "VCC1")
		(22 "In10.Cu" signal "GND4")
		(24 "In11.Cu" signal "IN4")
		(26 "In12.Cu" signal "GND5")
		(28 "In13.Cu" signal "IN5")
		(30 "In14.Cu" signal "GND6")
		(32 "In15.Cu" signal "IN6")
		(34 "In16.Cu" signal "GND7")
		(2 "B.Cu" signal "BOTTOM")
		(9 "F.Adhes" user "F.Adhesive")
		(11 "B.Adhes" user "B.Adhesive")
		(13 "F.Paste" user "Package Geometry/Pastemask Top")
		(15 "B.Paste" user "Package Geometry/Pastemask Bottom")
		(5 "F.SilkS" user "Ref Des/Silkscreen Top")
		(7 "B.SilkS" user "Ref Des/Silkscreen Bottom")
		(1 "F.Mask" user "Board Geometry/Soldermask Top")
		(3 "B.Mask" user "Board Geometry/Soldermask Bottom")
		(17 "Dwgs.User" user "User.Drawings")
		(19 "Cmts.User" user "User.Comments")
		(21 "Eco1.User" user "User.Eco1")
		(23 "Eco2.User" user "User.Eco2")
		(25 "Edge.Cuts" user "Board Geometry/Outline")
		(27 "Margin" user)
		(31 "F.CrtYd" user "Package Geometry/Place Bound Top")
		(29 "B.CrtYd" user "Package Geometry/Place Bound Bottom")
		(35 "F.Fab" user "Ref Des/Assembly Top")
		(33 "B.Fab" user "Ref Des/Assembly Bottom")
	)
	(footprint ""
		(layer "F.Cu")
		(at 154.23261 -57.436004)
		(property "Reference" "U98"
			(at -1.397 -2.13233 0)
			(unlocked yes)
			(layer "F.SilkS")
			(effects
				(font
					(size 0.7874 0.5842)
					(thickness 0.1524)
				)
				(justify left)
			)
		)
		(property "Value" ""
			(at 0 0 0)
			(layer "F.Fab")
			(effects
				(font
					(size 1.27 1.27)
				)
			)
		)
		(duplicate_pad_numbers_are_jumpers no)
		(fp_line
			(start -1.3208 -1.525016)
			(end -0.508 -1.525016)
			(stroke
				(width 0.1524)
				(type default)
			)
			(layer "F.SilkS")
		)
		(fp_line
			(start -1.3208 1.525016)
			(end -1.3208 -1.525016)
			(stroke
				(width 0.1524)
				(type default)
			)
			(layer "F.SilkS")
		)
		(fp_line
			(start -0.508 -1.525016)
			(end 0 -0.999998)
			(stroke
				(width 0.1524)
				(type default)
			)
			(layer "F.SilkS")
		)
		(fp_line
			(start 0 -0.999998)
			(end 0.508 -1.525016)
			(stroke
				(width 0.1524)
				(type default)
			)
			(layer "F.SilkS")
		)
		(fp_line
			(start 0.508 -1.525016)
			(end 1.3208 -1.525016)
			(stroke
				(width 0.1524)
				(type default)
			)
			(layer "F.SilkS")
		)
		(fp_line
			(start 1.3208 -1.525016)
			(end 1.3208 1.525016)
			(stroke
				(width 0.1524)
				(type default)
			)
			(layer "F.SilkS")
		)
		(fp_line
			(start 1.3208 1.525016)
			(end -1.3208 1.525016)
			(stroke
				(width 0.1524)
				(type default)
			)
			(layer "F.SilkS")
		)
		(fp_poly
			(pts
				(xy -3.937 -0.635) (xy -3.937 -1.397) (xy -3.175 -1.016)
			)
			(stroke
				(width 0)
				(type default)
			)
			(fill yes)
			(layer "F.SilkS")
		)
		(fp_line
			(start -3.037078 -1.20777)
			(end -1.524 -1.20777)
			(stroke
				(width 0.1)
				(type default)
			)
			(layer "F.Fab")
		)
		(fp_line
			(start -3.037078 1.203706)
			(end -3.037078 -1.20777)
			(stroke
				(width 0.1)
				(type default)
			)
			(layer "F.Fab")
		)
		(fp_line
			(start -1.5494 1.203706)
			(end -3.037078 1.203706)
			(stroke
				(width 0.1)
				(type default)
			)
			(layer "F.Fab")
		)
		(fp_line
			(start -1.5494 1.5494)
			(end -1.5494 1.203706)
			(stroke
				(width 0.1)
				(type default)
			)
			(layer "F.Fab")
		)
		(fp_line
			(start -1.524 -1.524)
			(end 1.524 -1.524)
			(stroke
				(width 0.1)
				(type default)
			)
			(layer "F.Fab")
		)
		(fp_line
			(start -1.524 -1.20777)
			(end -1.524 -1.524)
			(stroke
				(width 0.1)
				(type default)
			)
			(layer "F.Fab")
		)
		(fp_line
			(start 1.524 -1.524)
			(end 1.524 -1.20777)
			(stroke
				(width 0.1)
				(type default)
			)
			(layer "F.Fab")
		)
		(fp_line
			(start 1.524 -1.20777)
			(end 3.0353 -1.20777)
			(stroke
				(width 0.1)
				(type default)
			)
			(layer "F.Fab")
		)
		(fp_line
			(start 1.524 1.208786)
			(end 1.524 1.5494)
			(stroke
				(width 0.1)
				(type default)
			)
			(layer "F.Fab")
		)
		(fp_line
			(start 1.524 1.5494)
			(end -1.5494 1.5494)
			(stroke
				(width 0.1)
				(type default)
			)
			(layer "F.Fab")
		)
		(fp_line
			(start 3.0353 -1.20777)
			(end 3.0353 1.208786)
			(stroke
				(width 0.1)
				(type default)
			)
			(layer "F.Fab")
		)
		(fp_line
			(start 3.0353 1.208786)
			(end 1.524 1.208786)
			(stroke
				(width 0.1)
				(type default)
			)
			(layer "F.Fab")
		)
		(fp_poly
			(pts
				(xy -3.175 -1.016) (xy -3.937 -0.635) (xy -3.937 -1.397)
			)
			(stroke
				(width 0)
				(type default)
			)
			(fill yes)
			(layer "F.Fab")
		)
		(pad "1" smd rect
			(at -2.234946 -0.975106 270)
			(size 0.3556 1.4986)
			(layers "F.Cu" "F.Mask" "F.Paste")
			(net "GND")
		)
		(pad "2" smd rect
			(at -2.234946 -0.32512 270)
			(size 0.3556 1.4986)
			(layers "F.Cu" "F.Mask" "F.Paste")
			(net "P1V8_PCH_AUX")
		)
		(pad "3" smd rect
			(at -2.234946 0.32512 270)
			(size 0.3556 1.4986)
			(layers "F.Cu" "F.Mask" "F.Paste")
			(net "SMB_M2_P0_1V8AUX_SCL_R")
		)
		(pad "4" smd rect
			(at -2.234946 0.975106 270)
			(size 0.3556 1.4986)
			(layers "F.Cu" "F.Mask" "F.Paste")
			(net "SMB_M2_P0_1V8AUX_SDA_R")
		)
		(pad "5" smd rect
			(at 2.234946 0.975106 270)
			(size 0.3556 1.4986)
			(layers "F.Cu" "F.Mask" "F.Paste")
			(net "SMB_SENSOR_M2_P0_3V3AUX_SDA")
		)
		(pad "6" smd rect
			(at 2.234946 0.32512 270)
			(size 0.3556 1.4986)
			(layers "F.Cu" "F.Mask" "F.Paste")
			(net "SMB_SENSOR_M2_P0_3V3AUX_SCL")
		)
		(pad "7" smd rect
			(at 2.234946 -0.32512 270)
			(size 0.3556 1.4986)
			(layers "F.Cu" "F.Mask" "F.Paste")
			(net "SMB_PCIE_M2_0_EN")
		)
		(pad "8" smd rect
			(at 2.234946 -0.975106 270)
			(size 0.3556 1.4986)
			(layers "F.Cu" "F.Mask" "F.Paste")
			(net "SMB_PCIE_M2_0_EN")
		)
	)
	(footprint ""
		(layer "F.Cu")
		(at 104.349804 -244.032024 90)
		(property "Reference" "C252"
			(at 0 0 90)
			(layer "F.SilkS")
			(hide yes)
			(effects
				(font
					(size 1.27 1.27)
				)
			)
		)
		(property "Value" ""
			(at 0 0 90)
			(layer "F.Fab")
			(effects
				(font
					(size 1.27 1.27)
				)
			)
		)
		(duplicate_pad_numbers_are_jumpers no)
		(fp_line
			(start 0.7874 -0.4064)
			(end 0.7874 0.4064)
			(stroke
				(width 0.1524)
				(type default)
			)
			(layer "F.SilkS")
		)
		(fp_line
			(start -0.7874 -0.4064)
			(end 0.7874 -0.4064)
			(stroke
				(width 0.1524)
				(type default)
			)
			(layer "F.SilkS")
		)
		(fp_line
			(start 0.7874 0.4064)
			(end -0.7874 0.4064)
			(stroke
				(width 0.1524)
				(type default)
			)
			(layer "F.SilkS")
		)
		(fp_line
			(start -0.7874 0.4064)
			(end -0.7874 -0.4064)
			(stroke
				(width 0.1524)
				(type default)
			)
			(layer "F.SilkS")
		)
		(fp_line
			(start -0.12065 -0.305054)
			(end -0.12065 -0.2794)
			(stroke
				(width 0.1)
				(type default)
			)
			(layer "F.Fab")
		)
		(fp_line
			(start -0.67945 -0.305054)
			(end -0.12065 -0.305054)
			(stroke
				(width 0.1)
				(type default)
			)
			(layer "F.Fab")
		)
		(fp_line
			(start 0.67945 -0.3048)
			(end 0.67945 0.3048)
			(stroke
				(width 0.1)
				(type default)
			)
			(layer "F.Fab")
		)
		(fp_line
			(start 0.12065 -0.3048)
			(end 0.67945 -0.3048)
			(stroke
				(width 0.1)
				(type default)
			)
			(layer "F.Fab")
		)
		(fp_line
			(start 0.12065 -0.2794)
			(end 0.12065 -0.3048)
			(stroke
				(width 0.1)
				(type default)
			)
			(layer "F.Fab")
		)
		(fp_line
			(start -0.12065 -0.2794)
			(end 0.12065 -0.2794)
			(stroke
				(width 0.1)
				(type default)
			)
			(layer "F.Fab")
		)
		(fp_line
			(start 0.120396 0.2794)
			(end -0.12065 0.2794)
			(stroke
				(width 0.1)
				(type default)
			)
			(layer "F.Fab")
		)
		(fp_line
			(start -0.12065 0.2794)
			(end -0.12065 0.3048)
			(stroke
				(width 0.1)
				(type default)
			)
			(layer "F.Fab")
		)
		(fp_line
			(start 0.67945 0.3048)
			(end 0.120396 0.3048)
			(stroke
				(width 0.1)
				(type default)
			)
			(layer "F.Fab")
		)
		(fp_line
			(start 0.120396 0.3048)
			(end 0.120396 0.2794)
			(stroke
				(width 0.1)
				(type default)
			)
			(layer "F.Fab")
		)
		(fp_line
			(start -0.12065 0.3048)
			(end -0.67945 0.3048)
			(stroke
				(width 0.1)
				(type default)
			)
			(layer "F.Fab")
		)
		(fp_line
			(start -0.67945 0.3048)
			(end -0.67945 -0.305054)
			(stroke
				(width 0.1)
				(type default)
			)
			(layer "F.Fab")
		)
		(pad "1" smd circle
			(at -0.40005 0 90)
			(size 0 0)
			(layers "F.Cu" "F.Mask" "F.Paste")
			(net "PVCCIN_CPU1")
		)
		(pad "2" smd circle
			(at 0.40005 0 90)
			(size 0 0)
			(layers "F.Cu" "F.Mask" "F.Paste")
			(net "GND")
		)
	)
)
